(kicad_pcb
	(version 20221018)
	(generator pcbnew)
	(general
    (thickness 1.62)
  )
	(paper "A4")
	(title_block
    (title "ECP5 - Datacenter Secure Control Module (DC-SCM)")
    (date "2024-07-01")
    (rev "1.2.1")
		(comment 9 "footprints 134-141 of 506")
	)
	(layers
    (0 "F.Cu" signal)
    (1 "In1.Cu" power)
    (2 "In2.Cu" signal)
    (3 "In3.Cu" power)
    (4 "In4.Cu" power)
    (5 "In5.Cu" signal)
    (6 "In6.Cu" power)
    (31 "B.Cu" signal)
    (32 "B.Adhes" user "B.Adhesive")
    (33 "F.Adhes" user "F.Adhesive")
    (34 "B.Paste" user)
    (35 "F.Paste" user)
    (36 "B.SilkS" user "B.Silkscreen")
    (37 "F.SilkS" user "F.Silkscreen")
    (38 "B.Mask" user)
    (39 "F.Mask" user)
    (40 "Dwgs.User" user "User.Drawings")
    (41 "Cmts.User" user "User.Comments")
    (42 "Eco1.User" user "User.Eco1")
    (43 "Eco2.User" user "User.Eco2")
    (44 "Edge.Cuts" user)
    (45 "Margin" user)
    (46 "B.CrtYd" user "B.Courtyard")
    (47 "F.CrtYd" user "F.Courtyard")
    (48 "B.Fab" user)
    (49 "F.Fab" user)
  )
	(footprint "antmicro-footprints:C_0402_1005Metric" (layer "F.Cu")
    (at 80.05 83.925)
    (descr "Capacitor SMD 0402")
    (tags "capacitor SMD 0402")
    (property "Author" "Antmicro")
    (property "Dielectric" "")
    (property "License" "Apache-2.0")
    (property "MPN" "CC0402MRX5R5BB106")
    (property "Manufacturer" "YAGEO")
    (property "Public" "False")
    (property "Sheetfile" "power-supply.kicad_sch")
    (property "Sheetname" "Power supply")
    (property "Val" "10u")
    (property "Voltage" "")
    (property "ki_description" "SMD Multilayer Ceramic Capacitor, 10 µF, 6.3 V, 0402 [1005 Metric], ± 20%, X5R, CC Series")
    (property "ki_keywords" "0402, SMT, CAPACITOR, PASSIVE, MLCC, CERAMIC")
    (attr smd)
    (fp_text reference "C125" (at -0.82 -1.24) (layer "F.SilkS")
        (effects (font (size 0.7 0.7) (thickness 0.127)))
    )
    (fp_text value "C_10u_0402" (at 0 1.17) (layer "F.Fab")
        (effects (font (size 1 1) (thickness 0.15)))
    )
    (fp_text user "License: Apache-2.0" (at -0.939 5.799) (layer "F.Fab") hide
        (effects (font (size 0.7 0.7) (thickness 0.15)) (justify left bottom))
    )
    (fp_text user "Author: Antmicro" (at -0.939 3.399) (layer "F.Fab") hide
        (effects (font (size 0.7 0.7) (thickness 0.15)) (justify left bottom))
    )
    (fp_text user "${REFERENCE}" (at 0 0) (layer "F.Fab")
        (effects (font (size 0.25 0.25) (thickness 0.04)))
    )
    (fp_rect (start -0.925 -0.47) (end 0.925 0.47)
      (stroke (width 0.05) (type default)) (fill none) (layer "F.CrtYd"))
    (fp_line (start -0.494 -0.25) (end 0.504 -0.25)
      (stroke (width 0.15) (type solid)) (layer "F.Fab"))
    (fp_line (start -0.494 0.248) (end -0.494 -0.25)
      (stroke (width 0.15) (type solid)) (layer "F.Fab"))
    (fp_line (start 0.504 -0.25) (end 0.504 0.248)
      (stroke (width 0.15) (type solid)) (layer "F.Fab"))
    (fp_line (start 0.504 0.248) (end -0.494 0.248)
      (stroke (width 0.15) (type solid)) (layer "F.Fab"))
    (pad "1" smd roundrect (at -0.48 0) (size 0.59 0.64) (layers "F.Cu" "F.Paste" "F.Mask") (roundrect_rratio 0.25)
      (net 1 "GND") (pintype "passive"))
    (pad "2" smd roundrect (at 0.48 0) (size 0.59 0.64) (layers "F.Cu" "F.Paste" "F.Mask") (roundrect_rratio 0.25)
      (net 357 "Net-(C120-Pad2)") (pintype "passive"))
  )
	(footprint "antmicro-footprints:C_0402_1005Metric" (layer "F.Cu")
    (at 74.04 83.945)
    (descr "Capacitor SMD 0402")
    (tags "capacitor SMD 0402")
    (property "Author" "Antmicro")
    (property "Dielectric" "")
    (property "License" "Apache-2.0")
    (property "MPN" "CC0402MRX5R5BB106")
    (property "Manufacturer" "YAGEO")
    (property "Public" "False")
    (property "Sheetfile" "power-supply.kicad_sch")
    (property "Sheetname" "Power supply")
    (property "Val" "10u")
    (property "Voltage" "")
    (property "ki_description" "SMD Multilayer Ceramic Capacitor, 10 µF, 6.3 V, 0402 [1005 Metric], ± 20%, X5R, CC Series")
    (property "ki_keywords" "0402, SMT, CAPACITOR, PASSIVE, MLCC, CERAMIC")
    (attr smd)
    (fp_text reference "C126" (at -0.79 -1.28) (layer "F.SilkS")
        (effects (font (size 0.7 0.7) (thickness 0.127)))
    )
    (fp_text value "C_10u_0402" (at 0 1.17) (layer "F.Fab")
        (effects (font (size 1 1) (thickness 0.15)))
    )
    (fp_text user "License: Apache-2.0" (at -0.939 5.799) (layer "F.Fab") hide
        (effects (font (size 0.7 0.7) (thickness 0.15)) (justify left bottom))
    )
    (fp_text user "Author: Antmicro" (at -0.939 3.399) (layer "F.Fab") hide
        (effects (font (size 0.7 0.7) (thickness 0.15)) (justify left bottom))
    )
    (fp_text user "${REFERENCE}" (at 0 0) (layer "F.Fab")
        (effects (font (size 0.25 0.25) (thickness 0.04)))
    )
    (fp_rect (start -0.925 -0.47) (end 0.925 0.47)
      (stroke (width 0.05) (type default)) (fill none) (layer "F.CrtYd"))
    (fp_line (start -0.494 -0.25) (end 0.504 -0.25)
      (stroke (width 0.15) (type solid)) (layer "F.Fab"))
    (fp_line (start -0.494 0.248) (end -0.494 -0.25)
      (stroke (width 0.15) (type solid)) (layer "F.Fab"))
    (fp_line (start 0.504 -0.25) (end 0.504 0.248)
      (stroke (width 0.15) (type solid)) (layer "F.Fab"))
    (fp_line (start 0.504 0.248) (end -0.494 0.248)
      (stroke (width 0.15) (type solid)) (layer "F.Fab"))
    (pad "1" smd roundrect (at -0.48 0) (size 0.59 0.64) (layers "F.Cu" "F.Paste" "F.Mask") (roundrect_rratio 0.25)
      (net 1 "GND") (pintype "passive"))
    (pad "2" smd roundrect (at 0.48 0) (size 0.59 0.64) (layers "F.Cu" "F.Paste" "F.Mask") (roundrect_rratio 0.25)
      (net 358 "Net-(C121-Pad2)") (pintype "passive"))
  )
	(footprint "antmicro-footprints:C_0402_1005Metric" (layer "F.Cu")
    (at 120.539056 81.415)
    (descr "Capacitor SMD 0402")
    (tags "capacitor SMD 0402")
    (property "Author" "Antmicro")
    (property "Dielectric" "")
    (property "License" "Apache-2.0")
    (property "MPN" "CC0402MRX5R5BB106")
    (property "Manufacturer" "YAGEO")
    (property "Public" "False")
    (property "Sheetfile" "power-supply.kicad_sch")
    (property "Sheetname" "Power supply")
    (property "Val" "10u")
    (property "Voltage" "")
    (property "ki_description" "SMD Multilayer Ceramic Capacitor, 10 µF, 6.3 V, 0402 [1005 Metric], ± 20%, X5R, CC Series")
    (property "ki_keywords" "0402, SMT, CAPACITOR, PASSIVE, MLCC, CERAMIC")
    (attr smd)
    (fp_text reference "C124" (at 2.280944 0) (layer "F.SilkS")
        (effects (font (size 0.7 0.7) (thickness 0.127)))
    )
    (fp_text value "C_10u_0402" (at 0 1.17) (layer "F.Fab")
        (effects (font (size 1 1) (thickness 0.15)))
    )
    (fp_text user "Author: Antmicro" (at -0.939 3.399) (layer "F.Fab") hide
        (effects (font (size 0.7 0.7) (thickness 0.15)) (justify left bottom))
    )
    (fp_text user "${REFERENCE}" (at 0 0) (layer "F.Fab")
        (effects (font (size 0.25 0.25) (thickness 0.04)))
    )
    (fp_text user "License: Apache-2.0" (at -0.939 5.799) (layer "F.Fab") hide
        (effects (font (size 0.7 0.7) (thickness 0.15)) (justify left bottom))
    )
    (fp_rect (start -0.925 -0.47) (end 0.925 0.47)
      (stroke (width 0.05) (type default)) (fill none) (layer "F.CrtYd"))
    (fp_line (start -0.494 -0.25) (end 0.504 -0.25)
      (stroke (width 0.15) (type solid)) (layer "F.Fab"))
    (fp_line (start -0.494 0.248) (end -0.494 -0.25)
      (stroke (width 0.15) (type solid)) (layer "F.Fab"))
    (fp_line (start 0.504 -0.25) (end 0.504 0.248)
      (stroke (width 0.15) (type solid)) (layer "F.Fab"))
    (fp_line (start 0.504 0.248) (end -0.494 0.248)
      (stroke (width 0.15) (type solid)) (layer "F.Fab"))
    (pad "1" smd roundrect (at -0.48 0) (size 0.59 0.64) (layers "F.Cu" "F.Paste" "F.Mask") (roundrect_rratio 0.25)
      (net 1 "GND") (pintype "passive"))
    (pad "2" smd roundrect (at 0.48 0) (size 0.59 0.64) (layers "F.Cu" "F.Paste" "F.Mask") (roundrect_rratio 0.25)
      (net 356 "Net-(C119-Pad2)") (pintype "passive"))
  )
	(footprint "antmicro-footprints:C_0402_1005Metric" (layer "F.Cu")
    (at 86.04 83.945)
    (descr "Capacitor SMD 0402")
    (tags "capacitor SMD 0402")
    (property "Author" "Antmicro")
    (property "Dielectric" "")
    (property "License" "Apache-2.0")
    (property "MPN" "CC0402MRX5R5BB106")
    (property "Manufacturer" "YAGEO")
    (property "Public" "False")
    (property "Sheetfile" "power-supply.kicad_sch")
    (property "Sheetname" "Power supply")
    (property "Val" "10u")
    (property "Voltage" "")
    (property "ki_description" "SMD Multilayer Ceramic Capacitor, 10 µF, 6.3 V, 0402 [1005 Metric], ± 20%, X5R, CC Series")
    (property "ki_keywords" "0402, SMT, CAPACITOR, PASSIVE, MLCC, CERAMIC")
    (attr smd)
    (fp_text reference "C123" (at -0.6 -1.27) (layer "F.SilkS")
        (effects (font (size 0.7 0.7) (thickness 0.127)))
    )
    (fp_text value "C_10u_0402" (at 0 1.17) (layer "F.Fab")
        (effects (font (size 1 1) (thickness 0.15)))
    )
    (fp_text user "License: Apache-2.0" (at -0.939 5.799) (layer "F.Fab") hide
        (effects (font (size 0.7 0.7) (thickness 0.15)) (justify left bottom))
    )
    (fp_text user "Author: Antmicro" (at -0.939 3.399) (layer "F.Fab") hide
        (effects (font (size 0.7 0.7) (thickness 0.15)) (justify left bottom))
    )
    (fp_text user "${REFERENCE}" (at 0 0) (layer "F.Fab")
        (effects (font (size 0.25 0.25) (thickness 0.04)))
    )
    (fp_rect (start -0.925 -0.47) (end 0.925 0.47)
      (stroke (width 0.05) (type default)) (fill none) (layer "F.CrtYd"))
    (fp_line (start -0.494 -0.25) (end 0.504 -0.25)
      (stroke (width 0.15) (type solid)) (layer "F.Fab"))
    (fp_line (start -0.494 0.248) (end -0.494 -0.25)
      (stroke (width 0.15) (type solid)) (layer "F.Fab"))
    (fp_line (start 0.504 -0.25) (end 0.504 0.248)
      (stroke (width 0.15) (type solid)) (layer "F.Fab"))
    (fp_line (start 0.504 0.248) (end -0.494 0.248)
      (stroke (width 0.15) (type solid)) (layer "F.Fab"))
    (pad "1" smd roundrect (at -0.48 0) (size 0.59 0.64) (layers "F.Cu" "F.Paste" "F.Mask") (roundrect_rratio 0.25)
      (net 1 "GND") (pintype "passive"))
    (pad "2" smd roundrect (at 0.48 0) (size 0.59 0.64) (layers "F.Cu" "F.Paste" "F.Mask") (roundrect_rratio 0.25)
      (net 355 "Net-(C118-Pad2)") (pintype "passive"))
  )
	(footprint "antmicro-footprints:C_0402_1005Metric" (layer "F.Cu")
    (at 78.75 89.75)
    (descr "Capacitor SMD 0402")
    (tags "capacitor SMD 0402")
    (property "Author" "Antmicro")
    (property "Dielectric" "C0G")
    (property "License" "Apache-2.0")
    (property "MPN" "C0402C121J5GACTU")
    (property "Manufacturer" "KEMET")
    (property "Public" "False")
    (property "Sheetfile" "power-supply.kicad_sch")
    (property "Sheetname" "Power supply")
    (property "Val" "120p")
    (property "Voltage" "100V")
    (property "ki_description" "120 pF ±2% 100V Ceramic Capacitor C0G, NP0 0402 (1005 Metric)")
    (property "ki_keywords" "0402, SMT, CAPACITOR, PASSIVE, CERAMIC, MLCC")
    (attr smd)
    (fp_text reference "C120" (at 1.88 1.915) (layer "F.SilkS")
        (effects (font (size 0.7 0.7) (thickness 0.127)))
    )
    (fp_text value "C_120p_0402" (at 0 1.17) (layer "F.Fab")
        (effects (font (size 1 1) (thickness 0.15)))
    )
    (fp_text user "Author: Antmicro" (at -0.939 3.399) (layer "F.Fab") hide
        (effects (font (size 0.7 0.7) (thickness 0.15)) (justify left bottom))
    )
    (fp_text user "${REFERENCE}" (at 0 0) (layer "F.Fab")
        (effects (font (size 0.25 0.25) (thickness 0.04)))
    )
    (fp_text user "License: Apache-2.0" (at -0.939 5.799) (layer "F.Fab") hide
        (effects (font (size 0.7 0.7) (thickness 0.15)) (justify left bottom))
    )
    (fp_rect (start -0.925 -0.47) (end 0.925 0.47)
      (stroke (width 0.05) (type default)) (fill none) (layer "F.CrtYd"))
    (fp_line (start -0.494 -0.25) (end 0.504 -0.25)
      (stroke (width 0.15) (type solid)) (layer "F.Fab"))
    (fp_line (start -0.494 0.248) (end -0.494 -0.25)
      (stroke (width 0.15) (type solid)) (layer "F.Fab"))
    (fp_line (start 0.504 -0.25) (end 0.504 0.248)
      (stroke (width 0.15) (type solid)) (layer "F.Fab"))
    (fp_line (start 0.504 0.248) (end -0.494 0.248)
      (stroke (width 0.15) (type solid)) (layer "F.Fab"))
    (pad "1" smd roundrect (at -0.48 0) (size 0.59 0.64) (layers "F.Cu" "F.Paste" "F.Mask") (roundrect_rratio 0.25)
      (net 299 "Net-(U19-FB)") (pintype "passive"))
    (pad "2" smd roundrect (at 0.48 0) (size 0.59 0.64) (layers "F.Cu" "F.Paste" "F.Mask") (roundrect_rratio 0.25)
      (net 357 "Net-(C120-Pad2)") (pintype "passive"))
  )
	(footprint "antmicro-footprints:C_0402_1005Metric" (layer "F.Cu")
    (at 72.65 89.75)
    (descr "Capacitor SMD 0402")
    (tags "capacitor SMD 0402")
    (property "Author" "Antmicro")
    (property "Dielectric" "C0G")
    (property "License" "Apache-2.0")
    (property "MPN" "C0402C121J5GACTU")
    (property "Manufacturer" "KEMET")
    (property "Public" "False")
    (property "Sheetfile" "power-supply.kicad_sch")
    (property "Sheetname" "Power supply")
    (property "Val" "120p")
    (property "Voltage" "100V")
    (property "ki_description" "120 pF ±2% 100V Ceramic Capacitor C0G, NP0 0402 (1005 Metric)")
    (property "ki_keywords" "0402, SMT, CAPACITOR, PASSIVE, CERAMIC, MLCC")
    (attr smd)
    (fp_text reference "C121" (at 0.02 1.625) (layer "F.SilkS")
        (effects (font (size 0.7 0.7) (thickness 0.127)))
    )
    (fp_text value "C_120p_0402" (at 0 1.17) (layer "F.Fab")
        (effects (font (size 1 1) (thickness 0.15)))
    )
    (fp_text user "${REFERENCE}" (at 0 0) (layer "F.Fab")
        (effects (font (size 0.25 0.25) (thickness 0.04)))
    )
    (fp_text user "License: Apache-2.0" (at -0.939 5.799) (layer "F.Fab") hide
        (effects (font (size 0.7 0.7) (thickness 0.15)) (justify left bottom))
    )
    (fp_text user "Author: Antmicro" (at -0.939 3.399) (layer "F.Fab") hide
        (effects (font (size 0.7 0.7) (thickness 0.15)) (justify left bottom))
    )
    (fp_rect (start -0.925 -0.47) (end 0.925 0.47)
      (stroke (width 0.05) (type default)) (fill none) (layer "F.CrtYd"))
    (fp_line (start -0.494 -0.25) (end 0.504 -0.25)
      (stroke (width 0.15) (type solid)) (layer "F.Fab"))
    (fp_line (start -0.494 0.248) (end -0.494 -0.25)
      (stroke (width 0.15) (type solid)) (layer "F.Fab"))
    (fp_line (start 0.504 -0.25) (end 0.504 0.248)
      (stroke (width 0.15) (type solid)) (layer "F.Fab"))
    (fp_line (start 0.504 0.248) (end -0.494 0.248)
      (stroke (width 0.15) (type solid)) (layer "F.Fab"))
    (pad "1" smd roundrect (at -0.48 0) (size 0.59 0.64) (layers "F.Cu" "F.Paste" "F.Mask") (roundrect_rratio 0.25)
      (net 300 "Net-(U20-FB)") (pintype "passive"))
    (pad "2" smd roundrect (at 0.48 0) (size 0.59 0.64) (layers "F.Cu" "F.Paste" "F.Mask") (roundrect_rratio 0.25)
      (net 358 "Net-(C121-Pad2)") (pintype "passive"))
  )
	(footprint "antmicro-footprints:C_0402_1005Metric" (layer "F.Cu")
    (at 119.589056 87.243104)
    (descr "Capacitor SMD 0402")
    (tags "capacitor SMD 0402")
    (property "Author" "Antmicro")
    (property "Dielectric" "C0G")
    (property "License" "Apache-2.0")
    (property "MPN" "C0402C121J5GACTU")
    (property "Manufacturer" "KEMET")
    (property "Public" "False")
    (property "Sheetfile" "power-supply.kicad_sch")
    (property "Sheetname" "Power supply")
    (property "Val" "120p")
    (property "Voltage" "100V")
    (property "ki_description" "120 pF ±2% 100V Ceramic Capacitor C0G, NP0 0402 (1005 Metric)")
    (property "ki_keywords" "0402, SMT, CAPACITOR, PASSIVE, CERAMIC, MLCC")
    (attr smd)
    (fp_text reference "C119" (at -0.079056 0.941896) (layer "F.SilkS")
        (effects (font (size 0.7 0.7) (thickness 0.127)))
    )
    (fp_text value "C_120p_0402" (at 0 1.17) (layer "F.Fab")
        (effects (font (size 1 1) (thickness 0.15)))
    )
    (fp_text user "Author: Antmicro" (at -0.939 3.399) (layer "F.Fab") hide
        (effects (font (size 0.7 0.7) (thickness 0.15)) (justify left bottom))
    )
    (fp_text user "${REFERENCE}" (at 0 0) (layer "F.Fab")
        (effects (font (size 0.25 0.25) (thickness 0.04)))
    )
    (fp_text user "License: Apache-2.0" (at -0.939 5.799) (layer "F.Fab") hide
        (effects (font (size 0.7 0.7) (thickness 0.15)) (justify left bottom))
    )
    (fp_rect (start -0.925 -0.47) (end 0.925 0.47)
      (stroke (width 0.05) (type default)) (fill none) (layer "F.CrtYd"))
    (fp_line (start -0.494 -0.25) (end 0.504 -0.25)
      (stroke (width 0.15) (type solid)) (layer "F.Fab"))
    (fp_line (start -0.494 0.248) (end -0.494 -0.25)
      (stroke (width 0.15) (type solid)) (layer "F.Fab"))
    (fp_line (start 0.504 -0.25) (end 0.504 0.248)
      (stroke (width 0.15) (type solid)) (layer "F.Fab"))
    (fp_line (start 0.504 0.248) (end -0.494 0.248)
      (stroke (width 0.15) (type solid)) (layer "F.Fab"))
    (pad "1" smd roundrect (at -0.48 0) (size 0.59 0.64) (layers "F.Cu" "F.Paste" "F.Mask") (roundrect_rratio 0.25)
      (net 292 "Net-(U18-FB)") (pintype "passive"))
    (pad "2" smd roundrect (at 0.48 0) (size 0.59 0.64) (layers "F.Cu" "F.Paste" "F.Mask") (roundrect_rratio 0.25)
      (net 356 "Net-(C119-Pad2)") (pintype "passive"))
  )
	(footprint "antmicro-footprints:C_0402_1005Metric" (layer "F.Cu")
    (at 84.6 89.75)
    (descr "Capacitor SMD 0402")
    (tags "capacitor SMD 0402")
    (property "Author" "Antmicro")
    (property "Dielectric" "C0G")
    (property "License" "Apache-2.0")
    (property "MPN" "C0402C121J5GACTU")
    (property "Manufacturer" "KEMET")
    (property "Public" "False")
    (property "Sheetfile" "power-supply.kicad_sch")
    (property "Sheetname" "Power supply")
    (property "Val" "120p")
    (property "Voltage" "100V")
    (property "ki_description" "120 pF ±2% 100V Ceramic Capacitor C0G, NP0 0402 (1005 Metric)")
    (property "ki_keywords" "0402, SMT, CAPACITOR, PASSIVE, CERAMIC, MLCC")
    (attr smd)
    (fp_text reference "C118" (at -0.1 -1.9) (layer "F.SilkS")
        (effects (font (size 0.7 0.7) (thickness 0.127)))
    )
    (fp_text value "C_120p_0402" (at 0 1.17) (layer "F.Fab")
        (effects (font (size 1 1) (thickness 0.15)))
    )
    (fp_text user "License: Apache-2.0" (at -0.939 5.799) (layer "F.Fab") hide
        (effects (font (size 0.7 0.7) (thickness 0.15)) (justify left bottom))
    )
    (fp_text user "Author: Antmicro" (at -0.939 3.399) (layer "F.Fab") hide
        (effects (font (size 0.7 0.7) (thickness 0.15)) (justify left bottom))
    )
    (fp_text user "${REFERENCE}" (at 0 0) (layer "F.Fab")
        (effects (font (size 0.25 0.25) (thickness 0.04)))
    )
    (fp_rect (start -0.925 -0.47) (end 0.925 0.47)
      (stroke (width 0.05) (type default)) (fill none) (layer "F.CrtYd"))
    (fp_line (start -0.494 -0.25) (end 0.504 -0.25)
      (stroke (width 0.15) (type solid)) (layer "F.Fab"))
    (fp_line (start -0.494 0.248) (end -0.494 -0.25)
      (stroke (width 0.15) (type solid)) (layer "F.Fab"))
    (fp_line (start 0.504 -0.25) (end 0.504 0.248)
      (stroke (width 0.15) (type solid)) (layer "F.Fab"))
    (fp_line (start 0.504 0.248) (end -0.494 0.248)
      (stroke (width 0.15) (type solid)) (layer "F.Fab"))
    (pad "1" smd roundrect (at -0.48 0) (size 0.59 0.64) (layers "F.Cu" "F.Paste" "F.Mask") (roundrect_rratio 0.25)
      (net 291 "Net-(U17-FB)") (pintype "passive"))
    (pad "2" smd roundrect (at 0.48 0) (size 0.59 0.64) (layers "F.Cu" "F.Paste" "F.Mask") (roundrect_rratio 0.25)
      (net 355 "Net-(C118-Pad2)") (pintype "passive"))
  )
)
